(kicad_pcb
	(version 20260206)
	(generator "pcbnew")
	(generator_version "10.0")
	(general
		(thickness 1.6)
		(legacy_teardrops no)
	)
	(paper "A4")
	(title_block
		(title "netronome-mezz — pcbd0082-001_rev01_jul9_a.brd")
		(comment 1 "Open CloudServer (Microsoft) / footprints 351-359 of 714")
	)
	(layers
		(0 "F.Cu" signal "TOP")
		(4 "In1.Cu" signal "02_GND")
		(6 "In2.Cu" signal "03_SIG")
		(8 "In3.Cu" signal "04_SIG")
		(10 "In4.Cu" signal "05_GND")
		(12 "In5.Cu" signal "06_PWR1")
		(14 "In6.Cu" signal "07_SIG")
		(16 "In7.Cu" signal "08_SIG")
		(18 "In8.Cu" signal "09_GND")
		(2 "B.Cu" signal "BOTTOM")
		(9 "F.Adhes" user "F.Adhesive")
		(11 "B.Adhes" user "B.Adhesive")
		(13 "F.Paste" user "Package Geometry/Pastemask Top")
		(15 "B.Paste" user "Package Geometry/Pastemask Bottom")
		(5 "F.SilkS" user "Ref Des/Silkscreen Top")
		(7 "B.SilkS" user "Ref Des/Silkscreen Bottom")
		(1 "F.Mask" user "Board Geometry/Soldermask Top")
		(3 "B.Mask" user "Board Geometry/Soldermask Bottom")
		(17 "Dwgs.User" user "User.Drawings")
		(19 "Cmts.User" user "User.Comments")
		(21 "Eco1.User" user "User.Eco1")
		(23 "Eco2.User" user "User.Eco2")
		(25 "Edge.Cuts" user "Board Geometry/Outline")
		(27 "Margin" user)
		(31 "F.CrtYd" user "Package Geometry/Place Bound Top")
		(29 "B.CrtYd" user "Package Geometry/Place Bound Bottom")
		(35 "F.Fab" user "Ref Des/Assembly Top")
		(33 "B.Fab" user "Ref Des/Assembly Bottom")
		(45 "User.4" user "COMPVAL_TYPE_BOTTOM")
	)
	(footprint ""
		(layer "B.Cu")
		(at 44.73702 15.042007 90)
		(property "Reference" "C271"
			(at 0 0 90)
			(layer "B.SilkS")
			(hide yes)
			(effects
				(font
					(size 1.27 1.27)
				)
				(justify mirror)
			)
		)
		(property "Value" ""
			(at 0 0 90)
			(layer "B.Fab")
			(effects
				(font
					(size 1.27 1.27)
				)
				(justify mirror)
			)
		)
		(duplicate_pad_numbers_are_jumpers no)
		(fp_circle
			(center 0 0)
			(end 0 0.104648)
			(stroke
				(width 0.1016)
				(type default)
			)
			(fill no)
			(layer "B.SilkS")
		)
		(fp_poly
			(pts
				(xy 0.381 -0.889) (xy 0.381 0.889) (xy -0.381 0.889) (xy -0.381 -0.889)
			)
			(stroke
				(width 0)
				(type default)
			)
			(fill no)
			(layer "B.CrtYd")
		)
		(fp_line
			(start 0.508 -1.016)
			(end 0.254 -1.016)
			(stroke
				(width 0.0254)
				(type default)
			)
			(layer "B.Fab")
		)
		(fp_line
			(start 0.254 -1.016)
			(end -0.508 -1.016)
			(stroke
				(width 0.0254)
				(type default)
			)
			(layer "B.Fab")
		)
		(fp_line
			(start -0.508 -1.016)
			(end -0.508 1.016)
			(stroke
				(width 0.0254)
				(type default)
			)
			(layer "B.Fab")
		)
		(fp_line
			(start 0.508 1.016)
			(end 0.508 -1.016)
			(stroke
				(width 0.0254)
				(type default)
			)
			(layer "B.Fab")
		)
		(fp_line
			(start -0.508 1.016)
			(end 0.508 1.016)
			(stroke
				(width 0.0254)
				(type default)
			)
			(layer "B.Fab")
		)
		(pad "1" smd custom
			(at 0 -0.500126 270)
			(size 0.127 0.127)
			(layers "B.Cu" "B.Mask" "B.Paste")
			(net "VDD_3.3V")
			(options
				(clearance outline)
				(anchor circle)
			)
			(primitives
				(gr_poly
					(pts
						(xy -0.1778 0.254) (xy 0.1778 0.254) (xy 0.254 0.1778) (xy 0.254 -0.1778) (xy 0.1778 -0.254) (xy -0.1778 -0.254)
						(xy -0.254 -0.1778) (xy -0.254 0.1778)
					)
					(width 0)
					(fill yes)
				)
			)
		)
		(pad "2" smd custom
			(at 0 0.500126 270)
			(size 0.127 0.127)
			(layers "B.Cu" "B.Mask" "B.Paste")
			(net "GND")
			(options
				(clearance outline)
				(anchor circle)
			)
			(primitives
				(gr_poly
					(pts
						(xy -0.1778 0.254) (xy 0.1778 0.254) (xy 0.254 0.1778) (xy 0.254 -0.1778) (xy 0.1778 -0.254) (xy -0.1778 -0.254)
						(xy -0.254 -0.1778) (xy -0.254 0.1778)
					)
					(width 0)
					(fill yes)
				)
			)
		)
	)
	(footprint ""
		(layer "B.Cu")
		(at 52.737004 5.042027 90)
		(property "Reference" "C41"
			(at 1.994027 -1.074674 270)
			(unlocked yes)
			(layer "B.SilkS")
			(effects
				(font
					(size 0.7874 0.5842)
					(thickness 0.127)
				)
				(justify mirror)
			)
		)
		(property "Value" ""
			(at 0 0 90)
			(layer "B.Fab")
			(effects
				(font
					(size 1.27 1.27)
				)
				(justify mirror)
			)
		)
		(duplicate_pad_numbers_are_jumpers no)
		(fp_circle
			(center 0 0)
			(end 0 0.104648)
			(stroke
				(width 0.1016)
				(type default)
			)
			(fill no)
			(layer "B.SilkS")
		)
		(fp_poly
			(pts
				(xy 0.381 -0.889) (xy 0.381 0.889) (xy -0.381 0.889) (xy -0.381 -0.889)
			)
			(stroke
				(width 0)
				(type default)
			)
			(fill no)
			(layer "B.CrtYd")
		)
		(fp_line
			(start 0.508 -1.016)
			(end 0.254 -1.016)
			(stroke
				(width 0.0254)
				(type default)
			)
			(layer "B.Fab")
		)
		(fp_line
			(start 0.254 -1.016)
			(end -0.508 -1.016)
			(stroke
				(width 0.0254)
				(type default)
			)
			(layer "B.Fab")
		)
		(fp_line
			(start -0.508 -1.016)
			(end -0.508 1.016)
			(stroke
				(width 0.0254)
				(type default)
			)
			(layer "B.Fab")
		)
		(fp_line
			(start 0.508 1.016)
			(end 0.508 -1.016)
			(stroke
				(width 0.0254)
				(type default)
			)
			(layer "B.Fab")
		)
		(fp_line
			(start -0.508 1.016)
			(end 0.508 1.016)
			(stroke
				(width 0.0254)
				(type default)
			)
			(layer "B.Fab")
		)
		(pad "1" smd custom
			(at 0 -0.500126 270)
			(size 0.127 0.127)
			(layers "B.Cu" "B.Mask" "B.Paste")
			(net "VDDAH_SERDES")
			(options
				(clearance outline)
				(anchor circle)
			)
			(primitives
				(gr_poly
					(pts
						(xy -0.1778 0.254) (xy 0.1778 0.254) (xy 0.254 0.1778) (xy 0.254 -0.1778) (xy 0.1778 -0.254) (xy -0.1778 -0.254)
						(xy -0.254 -0.1778) (xy -0.254 0.1778)
					)
					(width 0)
					(fill yes)
				)
			)
		)
		(pad "2" smd custom
			(at 0 0.500126 270)
			(size 0.127 0.127)
			(layers "B.Cu" "B.Mask" "B.Paste")
			(net "GND")
			(options
				(clearance outline)
				(anchor circle)
			)
			(primitives
				(gr_poly
					(pts
						(xy -0.1778 0.254) (xy 0.1778 0.254) (xy 0.254 0.1778) (xy 0.254 -0.1778) (xy 0.1778 -0.254) (xy -0.1778 -0.254)
						(xy -0.254 -0.1778) (xy -0.254 0.1778)
					)
					(width 0)
					(fill yes)
				)
			)
		)
	)
	(footprint ""
		(layer "B.Cu")
		(at 28.829 22.352 180)
		(property "Reference" "R53"
			(at 0 0 0)
			(layer "B.SilkS")
			(hide yes)
			(effects
				(font
					(size 1.27 1.27)
				)
				(justify mirror)
			)
		)
		(property "Value" "4.75K"
			(at 0.148158 1.3462 90)
			(unlocked yes)
			(layer "B.Fab")
			(hide yes)
			(effects
				(font
					(size 1.27 0.9652)
					(thickness 0.000001)
				)
				(justify left mirror)
			)
		)
		(property "Device Type" "REST4024"
			(at 0.148158 1.3462 90)
			(unlocked yes)
			(layer "B.Fab")
			(hide yes)
			(effects
				(font
					(size 1.27 0.9652)
					(thickness 0.000001)
				)
				(justify left mirror)
			)
		)
		(duplicate_pad_numbers_are_jumpers no)
		(fp_poly
			(pts
				(xy -0.635 1.0668) (xy -0.635 -1.0668) (xy 0.635 -1.0668) (xy 0.635 1.0668)
			)
			(stroke
				(width 0)
				(type default)
			)
			(fill no)
			(layer "B.CrtYd")
		)
		(fp_line
			(start 0.254 0.508)
			(end 0.254 -0.508)
			(stroke
				(width 0.0254)
				(type default)
			)
			(layer "B.Fab")
		)
		(fp_line
			(start 0.254 -0.508)
			(end -0.254 -0.508)
			(stroke
				(width 0.0254)
				(type default)
			)
			(layer "B.Fab")
		)
		(fp_line
			(start -0.254 0.508)
			(end 0.254 0.508)
			(stroke
				(width 0.0254)
				(type default)
			)
			(layer "B.Fab")
		)
		(fp_line
			(start -0.254 -0.508)
			(end -0.254 0.508)
			(stroke
				(width 0.0254)
				(type default)
			)
			(layer "B.Fab")
		)
		(pad "1" smd rect
			(at 0 -0.4191)
			(size 0.508 0.5334)
			(layers "B.Cu" "B.Mask" "B.Paste")
			(net "EXT_3.3V")
		)
		(pad "2" smd rect
			(at 0 0.4191)
			(size 0.508 0.5334)
			(layers "B.Cu" "B.Mask" "B.Paste")
			(net "CPLD_VERSION_2")
		)
		(zone
			(layer "B.Cu")
			(hatch none 0.5)
			(connect_pads
				(clearance 0)
			)
			(min_thickness 0.25)
			(keepout
				(tracks not_allowed)
				(vias allowed)
				(pads allowed)
				(copperpour not_allowed)
				(footprints allowed)
			)
			(placement
				(enabled no)
				(sheetname "")
			)
			(fill
				(thermal_gap 0.5)
				(thermal_bridge_width 0.5)
				(island_removal_mode 0)
			)
			(polygon
				(pts
					(xy 28.8544 22.3774) (xy 28.8544 22.3266) (xy 28.8036 22.3266) (xy 28.8036 22.3774)
				)
			)
		)
	)
	(footprint ""
		(layer "B.Cu")
		(at 41.275 18.558002 -90)
		(property "Reference" "R203"
			(at 0 0 90)
			(layer "B.SilkS")
			(hide yes)
			(effects
				(font
					(size 1.27 1.27)
				)
				(justify mirror)
			)
		)
		(property "Value" "39.0"
			(at 0.148158 1.3462 180)
			(unlocked yes)
			(layer "B.Fab")
			(hide yes)
			(effects
				(font
					(size 1.27 0.9652)
					(thickness 0.000001)
				)
				(justify left mirror)
			)
		)
		(property "Device Type" "REST0108"
			(at 0.148158 1.3462 180)
			(unlocked yes)
			(layer "B.Fab")
			(hide yes)
			(effects
				(font
					(size 1.27 0.9652)
					(thickness 0.000001)
				)
				(justify left mirror)
			)
		)
		(duplicate_pad_numbers_are_jumpers no)
		(fp_poly
			(pts
				(xy -0.635 1.0668) (xy -0.635 -1.0668) (xy 0.635 -1.0668) (xy 0.635 1.0668)
			)
			(stroke
				(width 0)
				(type default)
			)
			(fill no)
			(layer "B.CrtYd")
		)
		(fp_line
			(start -0.254 0.508)
			(end 0.254 0.508)
			(stroke
				(width 0.0254)
				(type default)
			)
			(layer "B.Fab")
		)
		(fp_line
			(start 0.254 0.508)
			(end 0.254 -0.508)
			(stroke
				(width 0.0254)
				(type default)
			)
			(layer "B.Fab")
		)
		(fp_line
			(start -0.254 -0.508)
			(end -0.254 0.508)
			(stroke
				(width 0.0254)
				(type default)
			)
			(layer "B.Fab")
		)
		(fp_line
			(start 0.254 -0.508)
			(end -0.254 -0.508)
			(stroke
				(width 0.0254)
				(type default)
			)
			(layer "B.Fab")
		)
		(pad "1" smd rect
			(at 0 -0.4191 90)
			(size 0.508 0.5334)
			(layers "B.Cu" "B.Mask" "B.Paste")
			(net "_NFP_SPI2_MOSI")
		)
		(pad "2" smd rect
			(at 0 0.4191 90)
			(size 0.508 0.5334)
			(layers "B.Cu" "B.Mask" "B.Paste")
			(net "NFP_SPI2_MOSI")
		)
		(zone
			(layer "B.Cu")
			(hatch none 0.5)
			(connect_pads
				(clearance 0)
			)
			(min_thickness 0.25)
			(keepout
				(tracks not_allowed)
				(vias allowed)
				(pads allowed)
				(copperpour not_allowed)
				(footprints allowed)
			)
			(placement
				(enabled no)
				(sheetname "")
			)
			(fill
				(thermal_gap 0.5)
				(thermal_bridge_width 0.5)
				(island_removal_mode 0)
			)
			(polygon
				(pts
					(xy 41.3004 18.532602) (xy 41.2496 18.532602) (xy 41.2496 18.583402) (xy 41.3004 18.583402)
				)
			)
		)
	)
	(footprint ""
		(layer "B.Cu")
		(at 73.025 40.386 90)
		(property "Reference" "C179"
			(at -1.27 1.87833 270)
			(unlocked yes)
			(layer "B.SilkS")
			(effects
				(font
					(size 0.7874 0.5842)
					(thickness 0.127)
				)
				(justify left mirror)
			)
		)
		(property "Value" ""
			(at 0 0 90)
			(layer "B.Fab")
			(effects
				(font
					(size 1.27 1.27)
				)
				(justify mirror)
			)
		)
		(duplicate_pad_numbers_are_jumpers no)
		(fp_circle
			(center 0 0)
			(end 0 0.508)
			(stroke
				(width 0.2032)
				(type default)
			)
			(fill no)
			(layer "B.SilkS")
		)
		(fp_poly
			(pts
				(xy 2.286 1.581404) (xy 2.286 -1.778) (xy -2.286 -1.778) (xy -2.286 1.778) (xy 1.474165 1.778) (xy 1.656004 1.596161)
				(xy 2.271243 1.596161)
			)
			(stroke
				(width 0)
				(type default)
			)
			(fill no)
			(layer "B.CrtYd")
		)
		(fp_line
			(start 1.524 -1.27)
			(end -1.524 -1.27)
			(stroke
				(width 0.0254)
				(type default)
			)
			(layer "B.Fab")
		)
		(fp_line
			(start -1.524 -1.27)
			(end -1.524 1.27)
			(stroke
				(width 0.0254)
				(type default)
			)
			(layer "B.Fab")
		)
		(fp_line
			(start 1.524 1.27)
			(end 1.524 -1.27)
			(stroke
				(width 0.0254)
				(type default)
			)
			(layer "B.Fab")
		)
		(fp_line
			(start -1.524 1.27)
			(end 1.524 1.27)
			(stroke
				(width 0.0254)
				(type default)
			)
			(layer "B.Fab")
		)
		(pad "1" smd rect
			(at 1.4224 0 180)
			(size 2.7432 1.3716)
			(layers "B.Cu" "B.Mask" "B.Paste")
			(net "EXT_12.0V")
		)
		(pad "2" smd rect
			(at -1.4224 0 180)
			(size 2.7432 1.3716)
			(layers "B.Cu" "B.Mask" "B.Paste")
			(net "GND")
		)
	)
	(footprint ""
		(layer "B.Cu")
		(at 82.65099 29.812996)
		(property "Reference" "V3_A-A01"
			(at 0 0 0)
			(layer "B.SilkS")
			(hide yes)
			(effects
				(font
					(size 1.27 1.27)
				)
				(justify mirror)
			)
		)
		(property "Value" ""
			(at 0 0 0)
			(layer "B.Fab")
			(effects
				(font
					(size 1.27 1.27)
				)
				(justify mirror)
			)
		)
		(duplicate_pad_numbers_are_jumpers no)
		(pad "1" thru_hole circle
			(at 0 0 180)
			(size 0.4572 0.4572)
			(drill 0.20574)
			(layers "*.Cu" "*.Mask")
			(remove_unused_layers no)
			(net "DDR0_32A_A1")
			(clearance 0.1143)
			(thermal_gap 0.1143)
		)
	)
	(footprint ""
		(layer "B.Cu")
		(at 38.711632 17.042003 180)
		(property "Reference" "R282"
			(at 0 0 0)
			(layer "B.SilkS")
			(hide yes)
			(effects
				(font
					(size 1.27 1.27)
				)
				(justify mirror)
			)
		)
		(property "Value" "100"
			(at 0.148158 1.3462 90)
			(unlocked yes)
			(layer "B.Fab")
			(hide yes)
			(effects
				(font
					(size 1.27 0.9652)
					(thickness 0.000001)
				)
				(justify left mirror)
			)
		)
		(property "Device Type" "REST4030"
			(at 0.148158 1.3462 90)
			(unlocked yes)
			(layer "B.Fab")
			(hide yes)
			(effects
				(font
					(size 1.27 0.9652)
					(thickness 0.000001)
				)
				(justify left mirror)
			)
		)
		(duplicate_pad_numbers_are_jumpers no)
		(fp_poly
			(pts
				(xy -0.635 1.0668) (xy -0.635 -1.0668) (xy 0.635 -1.0668) (xy 0.635 1.0668)
			)
			(stroke
				(width 0)
				(type default)
			)
			(fill no)
			(layer "B.CrtYd")
		)
		(fp_line
			(start 0.254 0.508)
			(end 0.254 -0.508)
			(stroke
				(width 0.0254)
				(type default)
			)
			(layer "B.Fab")
		)
		(fp_line
			(start 0.254 -0.508)
			(end -0.254 -0.508)
			(stroke
				(width 0.0254)
				(type default)
			)
			(layer "B.Fab")
		)
		(fp_line
			(start -0.254 0.508)
			(end 0.254 0.508)
			(stroke
				(width 0.0254)
				(type default)
			)
			(layer "B.Fab")
		)
		(fp_line
			(start -0.254 -0.508)
			(end -0.254 0.508)
			(stroke
				(width 0.0254)
				(type default)
			)
			(layer "B.Fab")
		)
		(pad "1" smd rect
			(at 0 -0.4191)
			(size 0.508 0.5334)
			(layers "B.Cu" "B.Mask" "B.Paste")
			(net "_NFP_ARM_SPI_FLASH_SEL")
		)
		(pad "2" smd rect
			(at 0 0.4191)
			(size 0.508 0.5334)
			(layers "B.Cu" "B.Mask" "B.Paste")
			(net "NFP_ARM_SPI_FLASH_SEL")
		)
		(zone
			(layer "B.Cu")
			(hatch none 0.5)
			(connect_pads
				(clearance 0)
			)
			(min_thickness 0.25)
			(keepout
				(tracks not_allowed)
				(vias allowed)
				(pads allowed)
				(copperpour not_allowed)
				(footprints allowed)
			)
			(placement
				(enabled no)
				(sheetname "")
			)
			(fill
				(thermal_gap 0.5)
				(thermal_bridge_width 0.5)
				(island_removal_mode 0)
			)
			(polygon
				(pts
					(xy 38.737032 17.067403) (xy 38.737032 17.016603) (xy 38.686232 17.016603) (xy 38.686232 17.067403)
				)
			)
		)
	)
	(footprint ""
		(layer "B.Cu")
		(at 49.00168 35.433 90)
		(property "Reference" "C33"
			(at -1.29667 0.6731 0)
			(unlocked yes)
			(layer "B.SilkS")
			(effects
				(font
					(size 0.7874 0.5842)
					(thickness 0.127)
				)
				(justify left mirror)
			)
		)
		(property "Value" "0.22UF"
			(at 0.148158 1.7526 0)
			(unlocked yes)
			(layer "B.Fab")
			(hide yes)
			(effects
				(font
					(size 1.27 0.9652)
					(thickness 0.000001)
				)
				(justify left mirror)
			)
		)
		(property "Device Type" "CAPC0022"
			(at 0.148158 1.7526 0)
			(unlocked yes)
			(layer "B.Fab")
			(hide yes)
			(effects
				(font
					(size 1.27 0.9652)
					(thickness 0.000001)
				)
				(justify left mirror)
			)
		)
		(duplicate_pad_numbers_are_jumpers no)
		(fp_circle
			(center 0 0)
			(end 0 0.127)
			(stroke
				(width 0.2032)
				(type default)
			)
			(fill no)
			(layer "B.SilkS")
		)
		(fp_poly
			(pts
				(xy -0.7874 -1.6637) (xy 0.7874 -1.6637) (xy 0.7874 1.6637) (xy -0.7874 1.6637)
			)
			(stroke
				(width 0)
				(type default)
			)
			(fill no)
			(layer "B.CrtYd")
		)
		(fp_line
			(start 0.4064 -0.7874)
			(end -0.4064 -0.7874)
			(stroke
				(width 0.0254)
				(type default)
			)
			(layer "B.Fab")
		)
		(fp_line
			(start -0.4064 -0.7874)
			(end -0.4064 0.8128)
			(stroke
				(width 0.0254)
				(type default)
			)
			(layer "B.Fab")
		)
		(fp_line
			(start 0.4064 0.8128)
			(end 0.4064 -0.7874)
			(stroke
				(width 0.0254)
				(type default)
			)
			(layer "B.Fab")
		)
		(fp_line
			(start -0.4064 0.8128)
			(end 0.4064 0.8128)
			(stroke
				(width 0.0254)
				(type default)
			)
			(layer "B.Fab")
		)
		(pad "1" smd rect
			(at 0 -0.8001 270)
			(size 0.8636 0.9652)
			(layers "B.Cu" "B.Mask" "B.Paste")
			(net "10N2232")
		)
		(pad "2" smd rect
			(at 0 0.8001 270)
			(size 0.8636 0.9652)
			(layers "B.Cu" "B.Mask" "B.Paste")
			(net "10N2233")
		)
		(zone
			(layer "B.Cu")
			(hatch none 0.5)
			(connect_pads
				(clearance 0)
			)
			(min_thickness 0.25)
			(keepout
				(tracks not_allowed)
				(vias allowed)
				(pads allowed)
				(copperpour not_allowed)
				(footprints allowed)
			)
			(placement
				(enabled no)
				(sheetname "")
			)
			(fill
				(thermal_gap 0.5)
				(thermal_bridge_width 0.5)
				(island_removal_mode 0)
			)
			(polygon
				(pts
					(xy 48.74768 35.3695) (xy 48.74768 35.4965) (xy 49.25568 35.4965) (xy 49.25568 35.3695)
				)
			)
		)
	)
	(footprint ""
		(layer "B.Cu")
		(at 41.737026 12.042013 90)
		(property "Reference" "R16"
			(at 0 0 90)
			(layer "B.SilkS")
			(hide yes)
			(effects
				(font
					(size 1.27 1.27)
				)
				(justify mirror)
			)
		)
		(property "Value" ""
			(at 0 0 90)
			(layer "B.Fab")
			(effects
				(font
					(size 1.27 1.27)
				)
				(justify mirror)
			)
		)
		(duplicate_pad_numbers_are_jumpers no)
		(fp_circle
			(center 0 0)
			(end 0 0.104648)
			(stroke
				(width 0.1016)
				(type default)
			)
			(fill no)
			(layer "B.SilkS")
		)
		(fp_poly
			(pts
				(xy 0.381 -0.889) (xy 0.381 0.889) (xy -0.381 0.889) (xy -0.381 -0.889)
			)
			(stroke
				(width 0)
				(type default)
			)
			(fill no)
			(layer "B.CrtYd")
		)
		(fp_line
			(start 0.508 -1.016)
			(end 0.254 -1.016)
			(stroke
				(width 0.0254)
				(type default)
			)
			(layer "B.Fab")
		)
		(fp_line
			(start 0.254 -1.016)
			(end -0.508 -1.016)
			(stroke
				(width 0.0254)
				(type default)
			)
			(layer "B.Fab")
		)
		(fp_line
			(start -0.508 -1.016)
			(end -0.508 1.016)
			(stroke
				(width 0.0254)
				(type default)
			)
			(layer "B.Fab")
		)
		(fp_line
			(start 0.508 1.016)
			(end 0.508 -1.016)
			(stroke
				(width 0.0254)
				(type default)
			)
			(layer "B.Fab")
		)
		(fp_line
			(start -0.508 1.016)
			(end 0.508 1.016)
			(stroke
				(width 0.0254)
				(type default)
			)
			(layer "B.Fab")
		)
		(pad "1" smd custom
			(at 0 -0.500126 270)
			(size 0.127 0.127)
			(layers "B.Cu" "B.Mask" "B.Paste")
			(net "NFP_FAIL_SAFE_BOOT_L")
			(options
				(clearance outline)
				(anchor circle)
			)
			(primitives
				(gr_poly
					(pts
						(xy -0.1778 0.254) (xy 0.1778 0.254) (xy 0.254 0.1778) (xy 0.254 -0.1778) (xy 0.1778 -0.254) (xy -0.1778 -0.254)
						(xy -0.254 -0.1778) (xy -0.254 0.1778)
					)
					(width 0)
					(fill yes)
				)
			)
		)
		(pad "2" smd custom
			(at 0 0.500126 270)
			(size 0.127 0.127)
			(layers "B.Cu" "B.Mask" "B.Paste")
			(net "GND")
			(options
				(clearance outline)
				(anchor circle)
			)
			(primitives
				(gr_poly
					(pts
						(xy -0.1778 0.254) (xy 0.1778 0.254) (xy 0.254 0.1778) (xy 0.254 -0.1778) (xy 0.1778 -0.254) (xy -0.1778 -0.254)
						(xy -0.254 -0.1778) (xy -0.254 0.1778)
					)
					(width 0)
					(fill yes)
				)
			)
		)
	)
)
